FILE_TYPE=LIBRARY_PARTS;
primitive 'MP5016GQHLZ';
  pin
    'EN':
      PIN_NUMBER='(9)';
      INPUT_LOAD='(-0.01,0.01)';
    'MODE':
      PIN_NUMBER='(5)';
      INPUT_LOAD='(-0.01,0.01)';
    'ILIMIT':
      PIN_NUMBER='(4)';
      OUTPUT_LOAD='(1.0,-1.0)';
    'GND':
      PIN_NUMBER='(3)';
      PINUSE='POWER';
      NO_LOAD_CHECK='Both';
      NO_IO_CHECK='Both';
      NO_ASSERT_CHECK='TRUE';
      NO_DIR_CHECK='TRUE';
      ALLOW_CONNECT='TRUE';
    'VCC':
      PIN_NUMBER='(1_2)';
      PINUSE='POWER';
      NO_LOAD_CHECK='Both';
      NO_IO_CHECK='Both';
      NO_ASSERT_CHECK='TRUE';
      NO_DIR_CHECK='TRUE';
      ALLOW_CONNECT='TRUE';
    'DV_DT':
      PIN_NUMBER='(10)';
      OUTPUT_LOAD='(1.0,-1.0)';
    'GATE':
      PIN_NUMBER='(8)';
      OUTPUT_LOAD='(1.0,-1.0)';
    'SOURCE':
      PIN_NUMBER='(6_7)';
      OUTPUT_LOAD='(1.0,-1.0)';
  end_pin;
  body
    PART_NAME='MP5016GQHLZ';
    BODY_NAME='MP5016GQHLZ';
    PHYS_DES_PREFIX='U';
    CLASS='IC';
  end_body;
end_primitive;

END.
